# T6G (Grand Teton) — schematic netlist excerpt (pin names and nets, part order shuffled) for the footprints in the layout excerpt that follows; sources: Cadence DE-HDL packaged netlist, KiCad conversion of 04192023_DAF0TMB3IC0_F0TG_MB_C_brd_V02_OCP.brd

U157  74LVC1G07GV  IC  pkg SC-74A_2-9X1-5  page 133
  NC1  = NC_U157_NC1
  A  = OCP_SFF_WAKE_BUFF_R_N
  GND  = GND
  Y  = IRQ_LVC3_WAKE_BUF_N
  VCC  = P3V3_AUX

R6806  Q_RES  0 5% CHIP  pkg 0402LF  page 81 : A = RST_RT_CPU0_P1_PERST_R_N ; B = RST_RT_CPU0_P1_PERST_R2_N

(kicad_pcb
	(version 20260206)
	(generator "pcbnew")
	(generator_version "10.0")
	(general
		(thickness 1.6)
		(legacy_teardrops no)
	)
	(paper "A4")
	(title_block
		(title "04192023_DAF0TMB3IC0_F0TG_MB_C_brd_V02_OCP.brd")
		(comment 1 "Grand Teton / footprints 2409-2410 of 8354")
	)
	(layers
		(0 "F.Cu" signal "TOP")
		(4 "In1.Cu" signal "GND")
		(6 "In2.Cu" signal "IN1")
		(8 "In3.Cu" signal "GND1")
		(10 "In4.Cu" signal "IN2")
		(12 "In5.Cu" signal "GND2")
		(14 "In6.Cu" signal "IN3")
		(16 "In7.Cu" signal "GND3")
		(18 "In8.Cu" signal "VCC")
		(20 "In9.Cu" signal "VCC1")
		(22 "In10.Cu" signal "GND4")
		(24 "In11.Cu" signal "IN4")
		(26 "In12.Cu" signal "GND5")
		(28 "In13.Cu" signal "IN5")
		(30 "In14.Cu" signal "GND6")
		(32 "In15.Cu" signal "IN6")
		(34 "In16.Cu" signal "GND7")
		(2 "B.Cu" signal "BOTTOM")
		(9 "F.Adhes" user "F.Adhesive")
		(11 "B.Adhes" user "B.Adhesive")
		(13 "F.Paste" user "Package Geometry/Pastemask Top")
		(15 "B.Paste" user "Package Geometry/Pastemask Bottom")
		(5 "F.SilkS" user "Ref Des/Silkscreen Top")
		(7 "B.SilkS" user "Ref Des/Silkscreen Bottom")
		(1 "F.Mask" user "Board Geometry/Soldermask Top")
		(3 "B.Mask" user "Board Geometry/Soldermask Bottom")
		(17 "Dwgs.User" user "User.Drawings")
		(19 "Cmts.User" user "User.Comments")
		(21 "Eco1.User" user "User.Eco1")
		(23 "Eco2.User" user "User.Eco2")
		(25 "Edge.Cuts" user "Board Geometry/Outline")
		(27 "Margin" user)
		(31 "F.CrtYd" user "Package Geometry/Place Bound Top")
		(29 "B.CrtYd" user "Package Geometry/Place Bound Bottom")
		(35 "F.Fab" user "Ref Des/Assembly Top")
		(33 "B.Fab" user "Ref Des/Assembly Bottom")
	)
	(footprint ""
		(layer "F.Cu")
		(at 162.218116 -33.723834 90)
		(property "Reference" "U157"
			(at -0.75946 -2.367788 90)
			(unlocked yes)
			(layer "F.SilkS")
			(effects
				(font
					(size 0.7874 0.5842)
					(thickness 0.1524)
				)
				(justify left)
			)
		)
		(property "Value" ""
			(at 0 0 90)
			(layer "F.Fab")
			(effects
				(font
					(size 1.27 1.27)
				)
			)
		)
		(duplicate_pad_numbers_are_jumpers no)
		(fp_line
			(start 1.733296 -1.549908)
			(end 0.660908 -1.549908)
			(stroke
				(width 0.1524)
				(type default)
			)
			(layer "F.SilkS")
		)
		(fp_line
			(start 0.660908 -1.549908)
			(end 0 -0.889)
			(stroke
				(width 0.1524)
				(type default)
			)
			(layer "F.SilkS")
		)
		(fp_line
			(start -0.660908 -1.549908)
			(end -1.733296 -1.549908)
			(stroke
				(width 0.1524)
				(type default)
			)
			(layer "F.SilkS")
		)
		(fp_line
			(start -1.733296 -1.549908)
			(end -1.733296 1.549908)
			(stroke
				(width 0.1524)
				(type default)
			)
			(layer "F.SilkS")
		)
		(fp_line
			(start 0 -0.889)
			(end -0.660908 -1.549908)
			(stroke
				(width 0.1524)
				(type default)
			)
			(layer "F.SilkS")
		)
		(fp_line
			(start 1.733296 1.549908)
			(end 1.733296 -1.549908)
			(stroke
				(width 0.1524)
				(type default)
			)
			(layer "F.SilkS")
		)
		(fp_line
			(start -1.733296 1.549908)
			(end 1.733296 1.549908)
			(stroke
				(width 0.1524)
				(type default)
			)
			(layer "F.SilkS")
		)
		(fp_poly
			(pts
				(xy -1.9304 -0.94996) (xy -2.4384 -0.69596) (xy -2.4384 -1.20396)
			)
			(stroke
				(width 0)
				(type default)
			)
			(fill yes)
			(layer "F.SilkS")
		)
		(fp_line
			(start 0.849884 -1.549908)
			(end -0.849884 -1.549908)
			(stroke
				(width 0.1)
				(type default)
			)
			(layer "F.Fab")
		)
		(fp_line
			(start -0.849884 -1.549908)
			(end -0.849884 1.549908)
			(stroke
				(width 0.1)
				(type default)
			)
			(layer "F.Fab")
		)
		(fp_line
			(start 0.849884 1.549908)
			(end 0.849884 -1.549908)
			(stroke
				(width 0.1)
				(type default)
			)
			(layer "F.Fab")
		)
		(fp_line
			(start -0.849884 1.549908)
			(end 0.849884 1.549908)
			(stroke
				(width 0.1)
				(type default)
			)
			(layer "F.Fab")
		)
		(fp_poly
			(pts
				(xy -2.4384 -1.20396) (xy -2.4384 -0.69596) (xy -1.9304 -0.94996)
			)
			(stroke
				(width 0)
				(type default)
			)
			(fill yes)
			(layer "F.Fab")
		)
		(pad "1" smd rect
			(at -1.199896 -0.94996)
			(size 0.5588 0.8128)
			(layers "F.Cu" "F.Mask" "F.Paste")
			(net "NC_U157_NC1")
		)
		(pad "2" smd rect
			(at -1.199896 0)
			(size 0.5588 0.8128)
			(layers "F.Cu" "F.Mask" "F.Paste")
			(net "OCP_SFF_WAKE_BUFF_R_N")
		)
		(pad "3" smd rect
			(at -1.199896 0.94996)
			(size 0.5588 0.8128)
			(layers "F.Cu" "F.Mask" "F.Paste")
			(net "GND")
		)
		(pad "4" smd rect
			(at 1.199896 0.94996)
			(size 0.5588 0.8128)
			(layers "F.Cu" "F.Mask" "F.Paste")
			(net "IRQ_LVC3_WAKE_BUF_N")
		)
		(pad "5" smd rect
			(at 1.199896 -0.94996)
			(size 0.5588 0.8128)
			(layers "F.Cu" "F.Mask" "F.Paste")
			(net "P3V3_AUX")
		)
	)
	(footprint ""
		(layer "F.Cu")
		(at 184.605422 -133.565646 -90)
		(property "Reference" "R6806"
			(at 0 0 270)
			(layer "F.SilkS")
			(hide yes)
			(effects
				(font
					(size 1.27 1.27)
				)
			)
		)
		(property "Value" ""
			(at 0 0 270)
			(layer "F.Fab")
			(effects
				(font
					(size 1.27 1.27)
				)
			)
		)
		(duplicate_pad_numbers_are_jumpers no)
		(fp_line
			(start -0.7874 0.4064)
			(end -0.7874 -0.4064)
			(stroke
				(width 0.1524)
				(type default)
			)
			(layer "F.SilkS")
		)
		(fp_line
			(start 0.7874 0.4064)
			(end -0.7874 0.4064)
			(stroke
				(width 0.1524)
				(type default)
			)
			(layer "F.SilkS")
		)
		(fp_line
			(start -0.7874 -0.4064)
			(end 0.7874 -0.4064)
			(stroke
				(width 0.1524)
				(type default)
			)
			(layer "F.SilkS")
		)
		(fp_line
			(start 0.7874 -0.4064)
			(end 0.7874 0.4064)
			(stroke
				(width 0.1524)
				(type default)
			)
			(layer "F.SilkS")
		)
		(fp_line
			(start -0.67945 0.3048)
			(end -0.67945 -0.305054)
			(stroke
				(width 0.1)
				(type default)
			)
			(layer "F.Fab")
		)
		(fp_line
			(start -0.12065 0.3048)
			(end -0.67945 0.3048)
			(stroke
				(width 0.1)
				(type default)
			)
			(layer "F.Fab")
		)
		(fp_line
			(start 0.120396 0.3048)
			(end 0.120396 0.2794)
			(stroke
				(width 0.1)
				(type default)
			)
			(layer "F.Fab")
		)
		(fp_line
			(start 0.67945 0.3048)
			(end 0.120396 0.3048)
			(stroke
				(width 0.1)
				(type default)
			)
			(layer "F.Fab")
		)
		(fp_line
			(start -0.12065 0.2794)
			(end -0.12065 0.3048)
			(stroke
				(width 0.1)
				(type default)
			)
			(layer "F.Fab")
		)
		(fp_line
			(start 0.120396 0.2794)
			(end -0.12065 0.2794)
			(stroke
				(width 0.1)
				(type default)
			)
			(layer "F.Fab")
		)
		(fp_line
			(start -0.12065 -0.2794)
			(end 0.12065 -0.2794)
			(stroke
				(width 0.1)
				(type default)
			)
			(layer "F.Fab")
		)
		(fp_line
			(start 0.12065 -0.2794)
			(end 0.12065 -0.3048)
			(stroke
				(width 0.1)
				(type default)
			)
			(layer "F.Fab")
		)
		(fp_line
			(start 0.12065 -0.3048)
			(end 0.67945 -0.3048)
			(stroke
				(width 0.1)
				(type default)
			)
			(layer "F.Fab")
		)
		(fp_line
			(start 0.67945 -0.3048)
			(end 0.67945 0.3048)
			(stroke
				(width 0.1)
				(type default)
			)
			(layer "F.Fab")
		)
		(fp_line
			(start -0.67945 -0.305054)
			(end -0.12065 -0.305054)
			(stroke
				(width 0.1)
				(type default)
			)
			(layer "F.Fab")
		)
		(fp_line
			(start -0.12065 -0.305054)
			(end -0.12065 -0.2794)
			(stroke
				(width 0.1)
				(type default)
			)
			(layer "F.Fab")
		)
		(pad "1" smd circle
			(at -0.40005 0 270)
			(size 0 0)
			(layers "F.Cu" "F.Mask" "F.Paste")
			(net "RST_RT_CPU0_P1_PERST_R_N")
		)
		(pad "2" smd circle
			(at 0.40005 0 270)
			(size 0 0)
			(layers "F.Cu" "F.Mask" "F.Paste")
			(net "RST_RT_CPU0_P1_PERST_R2_N")
		)
	)
)
